(kicad_pcb
	(version 20260206)
	(generator "pcbnew")
	(generator_version "10.0")
	(general
		(thickness 1.6)
		(legacy_teardrops no)
	)
	(paper "A4")
	(title_block
		(title "dpb — 14545-sa.0730WZS0815.brd")
		(comment 1 "Honey Badger (Wiwynn) / footprints 195-202 of 1066")
	)
	(layers
		(0 "F.Cu" signal "TOP")
		(4 "In1.Cu" signal "L2GND")
		(6 "In2.Cu" signal "L3")
		(8 "In3.Cu" signal "L4VCC")
		(10 "In4.Cu" signal "L5VCC")
		(12 "In5.Cu" signal "L6")
		(14 "In6.Cu" signal "L7GND")
		(2 "B.Cu" signal "BOTTOM")
		(9 "F.Adhes" user "F.Adhesive")
		(11 "B.Adhes" user "B.Adhesive")
		(13 "F.Paste" user "Package Geometry/Pastemask Top")
		(15 "B.Paste" user "Package Geometry/Pastemask Bottom")
		(5 "F.SilkS" user "Ref Des/Silkscreen Top")
		(7 "B.SilkS" user "Ref Des/Silkscreen Bottom")
		(1 "F.Mask" user "Board Geometry/Soldermask Top")
		(3 "B.Mask" user "Board Geometry/Soldermask Bottom")
		(17 "Dwgs.User" user "User.Drawings")
		(19 "Cmts.User" user "User.Comments")
		(21 "Eco1.User" user "User.Eco1")
		(23 "Eco2.User" user "User.Eco2")
		(25 "Edge.Cuts" user "Board Geometry/Outline")
		(27 "Margin" user)
		(31 "F.CrtYd" user "Package Geometry/Place Bound Top")
		(29 "B.CrtYd" user "Package Geometry/Place Bound Bottom")
		(35 "F.Fab" user "Ref Des/Assembly Top")
		(33 "B.Fab" user "Ref Des/Assembly Bottom")
	)
	(footprint ""
		(layer "F.Cu")
		(at 80.01 -405.638 -90)
		(property "Reference" "D21"
			(at 0 0 270)
			(layer "F.SilkS")
			(hide yes)
			(effects
				(font
					(size 1.27 1.27)
				)
			)
		)
		(property "Value" "RB551V30-1-GP"
			(at 0 -6.7818 270)
			(unlocked yes)
			(layer "F.Fab")
			(hide yes)
			(effects
				(font
					(size 1.016 1.016)
					(thickness 0.1524)
				)
			)
		)
		(property "Device Type" "SOD323AKH44"
			(at 0 -8.6868 270)
			(unlocked yes)
			(layer "F.Fab")
			(hide yes)
			(effects
				(font
					(size 1.016 1.016)
					(thickness 0.1524)
				)
			)
		)
		(duplicate_pad_numbers_are_jumpers no)
		(fp_line
			(start -0.889 2.159)
			(end -0.889 -1.9304)
			(stroke
				(width 0.1524)
				(type default)
			)
			(layer "F.SilkS")
		)
		(fp_line
			(start 0.889 2.159)
			(end -0.889 2.159)
			(stroke
				(width 0.1524)
				(type default)
			)
			(layer "F.SilkS")
		)
		(fp_line
			(start 0.762 2.0574)
			(end -0.762 2.0574)
			(stroke
				(width 0.508)
				(type default)
			)
			(layer "F.SilkS")
		)
		(fp_line
			(start -0.889 -1.9304)
			(end 0.889 -1.9304)
			(stroke
				(width 0.1524)
				(type default)
			)
			(layer "F.SilkS")
		)
		(fp_line
			(start 0.889 -1.9304)
			(end 0.889 2.159)
			(stroke
				(width 0.1524)
				(type default)
			)
			(layer "F.SilkS")
		)
		(fp_rect
			(start -1.016 2.3114)
			(end 1.016 -2.0066)
			(stroke
				(width 0)
				(type default)
			)
			(fill no)
			(layer "F.CrtYd")
		)
		(fp_poly
			(pts
				(xy -1.016 -2.0066) (xy 1.016 -2.0066) (xy 1.016 2.3114) (xy -1.016 2.3114)
			)
			(stroke
				(width 0)
				(type default)
			)
			(fill no)
			(layer "F.Fab")
		)
		(pad "A" smd rect
			(at 0 -1.143 270)
			(size 0.5588 1.016)
			(layers "F.Cu" "F.Mask" "F.Paste")
			(net "SW_HDD6_R")
		)
		(pad "K" smd rect
			(at 0 1.143 270)
			(size 0.5588 1.016)
			(layers "F.Cu" "F.Mask" "F.Paste")
			(net "SW_HDD6_N")
		)
	)
	(footprint ""
		(layer "F.Cu")
		(at 30.987746 -341.1347 90)
		(property "Reference" "R258"
			(at 0 0 90)
			(layer "F.SilkS")
			(hide yes)
			(effects
				(font
					(size 1.27 1.27)
				)
			)
		)
		(property "Value" "0R2J-2-GP"
			(at 0.064008 -3.993896 90)
			(unlocked yes)
			(layer "F.Fab")
			(hide yes)
			(effects
				(font
					(size 1.016 1.016)
					(thickness 0.1524)
				)
			)
		)
		(property "Device Type" "R402H16"
			(at 0.064008 -5.517896 90)
			(unlocked yes)
			(layer "F.Fab")
			(hide yes)
			(effects
				(font
					(size 1.016 1.016)
					(thickness 0.1524)
				)
			)
		)
		(duplicate_pad_numbers_are_jumpers no)
		(fp_line
			(start 0.508 -0.9398)
			(end -0.508 -0.9398)
			(stroke
				(width 0.1524)
				(type default)
			)
			(layer "F.SilkS")
		)
		(fp_line
			(start -0.508 -0.9398)
			(end -0.508 0.9398)
			(stroke
				(width 0.1524)
				(type default)
			)
			(layer "F.SilkS")
		)
		(fp_rect
			(start -0.508 0.9398)
			(end 0.508 -0.9398)
			(stroke
				(width 0)
				(type default)
			)
			(fill no)
			(layer "F.CrtYd")
		)
		(fp_rect
			(start -0.508 0.9398)
			(end 0.508 -0.9398)
			(stroke
				(width 0)
				(type default)
			)
			(fill no)
			(layer "F.Fab")
		)
		(pad "1" smd custom
			(at 0 -0.4445 90)
			(size 0.1397 0.1397)
			(layers "F.Cu" "F.Mask" "F.Paste")
			(net "FLT_NET_HDD11")
			(options
				(clearance outline)
				(anchor circle)
			)
			(primitives
				(gr_poly
					(pts
						(arc
							(start -0.1778 -0.2794)
							(mid -0.249642 -0.249642)
							(end -0.2794 -0.1778)
						)
						(arc
							(start -0.2794 0.1778)
							(mid -0.249642 0.249642)
							(end -0.1778 0.2794)
						)
						(arc
							(start 0.1778 0.2794)
							(mid 0.249642 0.249642)
							(end 0.2794 0.1778)
						)
						(arc
							(start 0.2794 -0.1778)
							(mid 0.249642 -0.249642)
							(end 0.1778 -0.2794)
						)
					)
					(width 0)
					(fill yes)
				)
			)
		)
		(pad "2" smd custom
			(at 0 0.4445 90)
			(size 0.1397 0.1397)
			(layers "F.Cu" "F.Mask" "F.Paste")
			(net "FLT_HDD11_DRIVE")
			(options
				(clearance outline)
				(anchor circle)
			)
			(primitives
				(gr_poly
					(pts
						(arc
							(start -0.1778 -0.2794)
							(mid -0.249642 -0.249642)
							(end -0.2794 -0.1778)
						)
						(arc
							(start -0.2794 0.1778)
							(mid -0.249642 0.249642)
							(end -0.1778 0.2794)
						)
						(arc
							(start 0.1778 0.2794)
							(mid 0.249642 0.249642)
							(end 0.2794 0.1778)
						)
						(arc
							(start 0.2794 -0.1778)
							(mid 0.249642 -0.249642)
							(end 0.1778 -0.2794)
						)
					)
					(width 0)
					(fill yes)
				)
			)
		)
	)
	(footprint ""
		(layer "F.Cu")
		(at 192.405 -92.075 90)
		(property "Reference" "D19"
			(at 0 0 90)
			(layer "F.SilkS")
			(hide yes)
			(effects
				(font
					(size 1.27 1.27)
				)
			)
		)
		(property "Value" "RB551V30-1-GP"
			(at 0 -6.7818 90)
			(unlocked yes)
			(layer "F.Fab")
			(hide yes)
			(effects
				(font
					(size 1.016 1.016)
					(thickness 0.1524)
				)
			)
		)
		(property "Device Type" "SOD323AKH44"
			(at 0 -8.6868 90)
			(unlocked yes)
			(layer "F.Fab")
			(hide yes)
			(effects
				(font
					(size 1.016 1.016)
					(thickness 0.1524)
				)
			)
		)
		(duplicate_pad_numbers_are_jumpers no)
		(fp_line
			(start 0.889 -1.9304)
			(end 0.889 2.159)
			(stroke
				(width 0.1524)
				(type default)
			)
			(layer "F.SilkS")
		)
		(fp_line
			(start -0.889 -1.9304)
			(end 0.889 -1.9304)
			(stroke
				(width 0.1524)
				(type default)
			)
			(layer "F.SilkS")
		)
		(fp_line
			(start 0.762 2.0574)
			(end -0.762 2.0574)
			(stroke
				(width 0.508)
				(type default)
			)
			(layer "F.SilkS")
		)
		(fp_line
			(start 0.889 2.159)
			(end -0.889 2.159)
			(stroke
				(width 0.1524)
				(type default)
			)
			(layer "F.SilkS")
		)
		(fp_line
			(start -0.889 2.159)
			(end -0.889 -1.9304)
			(stroke
				(width 0.1524)
				(type default)
			)
			(layer "F.SilkS")
		)
		(fp_rect
			(start -1.016 2.3114)
			(end 1.016 -2.0066)
			(stroke
				(width 0)
				(type default)
			)
			(fill no)
			(layer "F.CrtYd")
		)
		(fp_poly
			(pts
				(xy -1.016 -2.0066) (xy 1.016 -2.0066) (xy 1.016 2.3114) (xy -1.016 2.3114)
			)
			(stroke
				(width 0)
				(type default)
			)
			(fill no)
			(layer "F.Fab")
		)
		(pad "A" smd rect
			(at 0 -1.143 90)
			(size 0.5588 1.016)
			(layers "F.Cu" "F.Mask" "F.Paste")
			(net "SW_HDD4_R")
		)
		(pad "K" smd rect
			(at 0 1.143 90)
			(size 0.5588 1.016)
			(layers "F.Cu" "F.Mask" "F.Paste")
			(net "SW_HDD4_N")
		)
	)
	(footprint ""
		(layer "F.Cu")
		(at 200.164446 -461.425036 180)
		(property "Reference" "C347"
			(at 0 0 180)
			(layer "F.SilkS")
			(hide yes)
			(effects
				(font
					(size 1.27 1.27)
				)
			)
		)
		(property "Value" "SCD1U50V3KX-GP"
			(at 0 -2.8194 180)
			(unlocked yes)
			(layer "F.Fab")
			(hide yes)
			(effects
				(font
					(size 1.016 1.016)
					(thickness 0.1524)
				)
			)
		)
		(property "Device Type" "C603H36"
			(at 0 -4.3434 180)
			(unlocked yes)
			(layer "F.Fab")
			(hide yes)
			(effects
				(font
					(size 1.016 1.016)
					(thickness 0.1524)
				)
			)
		)
		(duplicate_pad_numbers_are_jumpers no)
		(fp_line
			(start 0.508 0)
			(end -0.508 0)
			(stroke
				(width 0.2032)
				(type default)
			)
			(layer "F.SilkS")
		)
		(fp_rect
			(start -0.5842 1.3335)
			(end 0.5842 -1.3335)
			(stroke
				(width 0)
				(type default)
			)
			(fill no)
			(layer "F.CrtYd")
		)
		(fp_rect
			(start -0.5842 1.3335)
			(end 0.5842 -1.3335)
			(stroke
				(width 0)
				(type default)
			)
			(fill no)
			(layer "F.Fab")
		)
		(pad "1" smd custom
			(at 0 -0.762 180)
			(size 0.2159 0.2159)
			(layers "F.Cu" "F.Mask" "F.Paste")
			(net "P3V3")
			(options
				(clearance outline)
				(anchor circle)
			)
			(primitives
				(gr_poly
					(pts
						(arc
							(start -0.3302 -0.4318)
							(mid -0.402042 -0.402042)
							(end -0.4318 -0.3302)
						)
						(arc
							(start -0.4318 0.3302)
							(mid -0.402042 0.402042)
							(end -0.3302 0.4318)
						)
						(arc
							(start 0.3302 0.4318)
							(mid 0.402042 0.402042)
							(end 0.4318 0.3302)
						)
						(arc
							(start 0.4318 -0.3302)
							(mid 0.402042 -0.402042)
							(end 0.3302 -0.4318)
						)
					)
					(width 0)
					(fill yes)
				)
			)
		)
		(pad "2" smd custom
			(at 0 0.762 180)
			(size 0.2159 0.2159)
			(layers "F.Cu" "F.Mask" "F.Paste")
			(net "GND")
			(options
				(clearance outline)
				(anchor circle)
			)
			(primitives
				(gr_poly
					(pts
						(arc
							(start -0.3302 -0.4318)
							(mid -0.402042 -0.402042)
							(end -0.4318 -0.3302)
						)
						(arc
							(start -0.4318 0.3302)
							(mid -0.402042 0.402042)
							(end -0.3302 0.4318)
						)
						(arc
							(start 0.3302 0.4318)
							(mid 0.402042 0.402042)
							(end 0.4318 0.3302)
						)
						(arc
							(start 0.4318 -0.3302)
							(mid 0.402042 -0.402042)
							(end 0.3302 -0.4318)
						)
					)
					(width 0)
					(fill yes)
				)
			)
		)
	)
	(footprint ""
		(layer "F.Cu")
		(at 45.847 -349.1992 180)
		(property "Reference" "R187"
			(at 0 0 180)
			(layer "F.SilkS")
			(hide yes)
			(effects
				(font
					(size 1.27 1.27)
				)
			)
		)
		(property "Value" "330R2F-GP"
			(at 0.064008 -3.993896 180)
			(unlocked yes)
			(layer "F.Fab")
			(hide yes)
			(effects
				(font
					(size 1.016 1.016)
					(thickness 0.1524)
				)
			)
		)
		(property "Device Type" "R402H16"
			(at 0.064008 -5.517896 180)
			(unlocked yes)
			(layer "F.Fab")
			(hide yes)
			(effects
				(font
					(size 1.016 1.016)
					(thickness 0.1524)
				)
			)
		)
		(duplicate_pad_numbers_are_jumpers no)
		(fp_line
			(start 0.508 -0.9398)
			(end -0.508 -0.9398)
			(stroke
				(width 0.1524)
				(type default)
			)
			(layer "F.SilkS")
		)
		(fp_line
			(start -0.508 -0.9398)
			(end -0.508 0.9398)
			(stroke
				(width 0.1524)
				(type default)
			)
			(layer "F.SilkS")
		)
		(fp_rect
			(start -0.508 0.9398)
			(end 0.508 -0.9398)
			(stroke
				(width 0)
				(type default)
			)
			(fill no)
			(layer "F.CrtYd")
		)
		(fp_rect
			(start -0.508 0.9398)
			(end 0.508 -0.9398)
			(stroke
				(width 0)
				(type default)
			)
			(fill no)
			(layer "F.Fab")
		)
		(pad "1" smd custom
			(at 0 -0.4445 180)
			(size 0.1397 0.1397)
			(layers "F.Cu" "F.Mask" "F.Paste")
			(net "P3V3_HDD6_LED")
			(options
				(clearance outline)
				(anchor circle)
			)
			(primitives
				(gr_poly
					(pts
						(arc
							(start -0.1778 -0.2794)
							(mid -0.249642 -0.249642)
							(end -0.2794 -0.1778)
						)
						(arc
							(start -0.2794 0.1778)
							(mid -0.249642 0.249642)
							(end -0.1778 0.2794)
						)
						(arc
							(start 0.1778 0.2794)
							(mid 0.249642 0.249642)
							(end 0.2794 0.1778)
						)
						(arc
							(start 0.2794 -0.1778)
							(mid 0.249642 -0.249642)
							(end 0.1778 -0.2794)
						)
					)
					(width 0)
					(fill yes)
				)
			)
		)
		(pad "2" smd custom
			(at 0 0.4445 180)
			(size 0.1397 0.1397)
			(layers "F.Cu" "F.Mask" "F.Paste")
			(net "FLT_HDD6")
			(options
				(clearance outline)
				(anchor circle)
			)
			(primitives
				(gr_poly
					(pts
						(arc
							(start -0.1778 -0.2794)
							(mid -0.249642 -0.249642)
							(end -0.2794 -0.1778)
						)
						(arc
							(start -0.2794 0.1778)
							(mid -0.249642 0.249642)
							(end -0.1778 0.2794)
						)
						(arc
							(start 0.1778 0.2794)
							(mid 0.249642 0.249642)
							(end 0.2794 0.1778)
						)
						(arc
							(start 0.2794 -0.1778)
							(mid 0.249642 -0.249642)
							(end 0.1778 -0.2794)
						)
					)
					(width 0)
					(fill yes)
				)
			)
		)
	)
	(footprint ""
		(layer "F.Cu")
		(at 6.985 -231.648)
		(property "Reference" "R609"
			(at 0 0 0)
			(layer "F.SilkS")
			(hide yes)
			(effects
				(font
					(size 1.27 1.27)
				)
			)
		)
		(property "Value" "2R2010J-1-GP"
			(at 0.254 -8.0772 0)
			(unlocked yes)
			(layer "F.Fab")
			(hide yes)
			(effects
				(font
					(size 1.016 1.016)
					(thickness 0.1524)
				)
			)
		)
		(property "Device Type" "R2010H28"
			(at 0.254 -9.6774 0)
			(unlocked yes)
			(layer "F.Fab")
			(hide yes)
			(effects
				(font
					(size 1.016 1.016)
					(thickness 0.1524)
				)
			)
		)
		(duplicate_pad_numbers_are_jumpers no)
		(fp_line
			(start -1.651 -3.302)
			(end -1.651 3.302)
			(stroke
				(width 0.1524)
				(type default)
			)
			(layer "F.SilkS")
		)
		(fp_line
			(start -1.651 3.302)
			(end 1.651 3.302)
			(stroke
				(width 0.1524)
				(type default)
			)
			(layer "F.SilkS")
		)
		(fp_line
			(start 1.651 -3.302)
			(end -1.651 -3.302)
			(stroke
				(width 0.1524)
				(type default)
			)
			(layer "F.SilkS")
		)
		(fp_line
			(start 1.651 3.302)
			(end 1.651 -3.302)
			(stroke
				(width 0.1524)
				(type default)
			)
			(layer "F.SilkS")
		)
		(fp_rect
			(start -1.7272 -3.3782)
			(end 1.7272 3.3782)
			(stroke
				(width 0)
				(type default)
			)
			(fill no)
			(layer "F.CrtYd")
		)
		(fp_poly
			(pts
				(xy 1.7272 3.3782) (xy 1.7272 -3.3782) (xy -1.7272 -3.3782) (xy -1.7272 3.3782)
			)
			(stroke
				(width 0)
				(type default)
			)
			(fill no)
			(layer "F.Fab")
		)
		(pad "1" smd rect
			(at 0 -2.3495)
			(size 2.794 1.143)
			(layers "F.Cu" "F.Mask" "F.Paste")
			(net "GND")
		)
		(pad "2" smd rect
			(at 0 2.3495)
			(size 2.794 1.143)
			(layers "F.Cu" "F.Mask" "F.Paste")
			(net "PCIE_MATED#_B")
		)
	)
	(footprint ""
		(layer "F.Cu")
		(at 4.698746 -489.3437)
		(property "Reference" "R486"
			(at 0 0 0)
			(layer "F.SilkS")
			(hide yes)
			(effects
				(font
					(size 1.27 1.27)
				)
			)
		)
		(property "Value" "0R3J-0-U-GP"
			(at -0.0254 -2.5146 0)
			(unlocked yes)
			(layer "F.Fab")
			(hide yes)
			(effects
				(font
					(size 1.016 1.016)
					(thickness 0.1524)
				)
			)
		)
		(property "Device Type" "R603H22"
			(at -0.0254 -4.0386 0)
			(unlocked yes)
			(layer "F.Fab")
			(hide yes)
			(effects
				(font
					(size 1.016 1.016)
					(thickness 0.1524)
				)
			)
		)
		(duplicate_pad_numbers_are_jumpers no)
		(fp_line
			(start -0.4826 0)
			(end -0.2032 0)
			(stroke
				(width 0.2032)
				(type default)
			)
			(layer "F.SilkS")
		)
		(fp_line
			(start 0.2032 0)
			(end 0.4826 0)
			(stroke
				(width 0.2032)
				(type default)
			)
			(layer "F.SilkS")
		)
		(fp_rect
			(start -0.5842 1.3335)
			(end 0.5842 -1.3335)
			(stroke
				(width 0)
				(type default)
			)
			(fill no)
			(layer "F.CrtYd")
		)
		(fp_rect
			(start -0.5842 1.3335)
			(end 0.5842 -1.3335)
			(stroke
				(width 0)
				(type default)
			)
			(fill no)
			(layer "F.Fab")
		)
		(pad "1" smd custom
			(at 0 -0.762)
			(size 0.2159 0.2159)
			(layers "F.Cu" "F.Mask" "F.Paste")
			(net "P5VC_VBST")
			(options
				(clearance outline)
				(anchor circle)
			)
			(primitives
				(gr_poly
					(pts
						(arc
							(start -0.3302 -0.4318)
							(mid -0.402042 -0.402042)
							(end -0.4318 -0.3302)
						)
						(arc
							(start -0.4318 0.3302)
							(mid -0.402042 0.402042)
							(end -0.3302 0.4318)
						)
						(arc
							(start 0.3302 0.4318)
							(mid 0.402042 0.402042)
							(end 0.4318 0.3302)
						)
						(arc
							(start 0.4318 -0.3302)
							(mid 0.402042 -0.402042)
							(end 0.3302 -0.4318)
						)
					)
					(width 0)
					(fill yes)
				)
			)
		)
		(pad "2" smd custom
			(at 0 0.762)
			(size 0.2159 0.2159)
			(layers "F.Cu" "F.Mask" "F.Paste")
			(net "P5VC_VBST_NET")
			(options
				(clearance outline)
				(anchor circle)
			)
			(primitives
				(gr_poly
					(pts
						(arc
							(start -0.3302 -0.4318)
							(mid -0.402042 -0.402042)
							(end -0.4318 -0.3302)
						)
						(arc
							(start -0.4318 0.3302)
							(mid -0.402042 0.402042)
							(end -0.3302 0.4318)
						)
						(arc
							(start 0.3302 0.4318)
							(mid 0.402042 0.402042)
							(end 0.4318 0.3302)
						)
						(arc
							(start 0.4318 -0.3302)
							(mid 0.402042 -0.402042)
							(end 0.3302 -0.4318)
						)
					)
					(width 0)
					(fill yes)
				)
			)
		)
	)
	(footprint ""
		(layer "F.Cu")
		(at 50.050446 -414.175702 90)
		(property "Reference" "R249"
			(at 0 0 90)
			(layer "F.SilkS")
			(hide yes)
			(effects
				(font
					(size 1.27 1.27)
				)
			)
		)
		(property "Value" "200KR2F-L-GP"
			(at 0.064008 -3.993896 90)
			(unlocked yes)
			(layer "F.Fab")
			(hide yes)
			(effects
				(font
					(size 1.016 1.016)
					(thickness 0.1524)
				)
			)
		)
		(property "Device Type" "R402H16"
			(at 0.064008 -5.517896 90)
			(unlocked yes)
			(layer "F.Fab")
			(hide yes)
			(effects
				(font
					(size 1.016 1.016)
					(thickness 0.1524)
				)
			)
		)
		(duplicate_pad_numbers_are_jumpers no)
		(fp_line
			(start 0.508 -0.9398)
			(end -0.508 -0.9398)
			(stroke
				(width 0.1524)
				(type default)
			)
			(layer "F.SilkS")
		)
		(fp_line
			(start -0.508 -0.9398)
			(end -0.508 0.9398)
			(stroke
				(width 0.1524)
				(type default)
			)
			(layer "F.SilkS")
		)
		(fp_rect
			(start -0.508 0.9398)
			(end 0.508 -0.9398)
			(stroke
				(width 0)
				(type default)
			)
			(fill no)
			(layer "F.CrtYd")
		)
		(fp_rect
			(start -0.508 0.9398)
			(end 0.508 -0.9398)
			(stroke
				(width 0)
				(type default)
			)
			(fill no)
			(layer "F.Fab")
		)
		(pad "1" smd custom
			(at 0 -0.4445 90)
			(size 0.1397 0.1397)
			(layers "F.Cu" "F.Mask" "F.Paste")
			(net "P12V")
			(options
				(clearance outline)
				(anchor circle)
			)
			(primitives
				(gr_poly
					(pts
						(arc
							(start -0.1778 -0.2794)
							(mid -0.249642 -0.249642)
							(end -0.2794 -0.1778)
						)
						(arc
							(start -0.2794 0.1778)
							(mid -0.249642 0.249642)
							(end -0.1778 0.2794)
						)
						(arc
							(start 0.1778 0.2794)
							(mid 0.249642 0.249642)
							(end 0.2794 0.1778)
						)
						(arc
							(start 0.2794 -0.1778)
							(mid 0.249642 -0.249642)
							(end 0.1778 -0.2794)
						)
					)
					(width 0)
					(fill yes)
				)
			)
		)
		(pad "2" smd custom
			(at 0 0.4445 90)
			(size 0.1397 0.1397)
			(layers "F.Cu" "F.Mask" "F.Paste")
			(net "SW_HDD10_P")
			(options
				(clearance outline)
				(anchor circle)
			)
			(primitives
				(gr_poly
					(pts
						(arc
							(start -0.1778 -0.2794)
							(mid -0.249642 -0.249642)
							(end -0.2794 -0.1778)
						)
						(arc
							(start -0.2794 0.1778)
							(mid -0.249642 0.249642)
							(end -0.1778 0.2794)
						)
						(arc
							(start 0.1778 0.2794)
							(mid 0.249642 0.249642)
							(end 0.2794 0.1778)
						)
						(arc
							(start 0.2794 -0.1778)
							(mid 0.249642 -0.249642)
							(end 0.1778 -0.2794)
						)
					)
					(width 0)
					(fill yes)
				)
			)
		)
	)
)
